FILE_TYPE = MACRO_DRAWING;
SET COLOR_WIRE YELLOW;
SET COLOR_PROP MONO;
SET COLOR_DOT WHITE;
SET COLOR_ARC YELLOW;
SET COLOR_BODY GREEN;
SET COLOR_NOTE MONO;
SET PROP_DISPLAY VALUE;
SET PAGE_NUMBER P264;
FORCEADD INTEL_CORP_BPAGE..1
(-1450 1650);
FORCEPROP 1 LAST CDS_CON_LAST_MODIFIED Fri Jun 16 17:49:40 2017
J 0
(-2875 1975);
PAINT ORANGE (-2875 1975);
DISPLAY INVISIBLE (-2875 1975);
FORCEPROP 1 LAST CUSTOM_TXT_CDS <CURRENT_DESIGN_SHEET> OF <TOTAL_DESIGN_SHEETS>
J 0
(-1950 1675);
PAINT ORANGE (-1950 1675);
FORCEPROP 2 LAST CUSTOM_TXT_CDS <XR_PAGE_TITLE>
J 0
(-9340 6900);
DISPLAY 0.638298 (-9340 6900);
PAINT PINK (-9340 6900);
DISPLAY INVISIBLE (-9340 6900);
FORCEPROP 2 LAST CUSTOM_TXT_CDS <CON_LAST_MODIFIED>
J 0
(-5450 1750);
PAINT ORANGE (-5450 1750);
FORCEPROP 1 LAST SCH_TITLE FAST PROCHOT BLOCK DIAGRAM
J 0
(-9400 1700);
DISPLAY 2.468085 (-9400 1700);
PAINT ORANGE (-9400 1700);
FORCEPROP 2 LAST PAGE_BORDER TRUE
J 0
(-9340 6900);
DISPLAY 0.638298 (-9340 6900);
PAINT PINK (-9340 6900);
DISPLAY INVISIBLE (-9340 6900);
FORCEPROP 2 LAST CDS_LIB mstr_symbols
J 0
(-1450 1650);
PAINT MONO (-1450 1650);
DISPLAY INVISIBLE (-1450 1650);
FORCEPROP 1 LAST COMMENT_BODY TRUE
J 0
(-1438 1662);
DISPLAY 0.468085 (-1438 1662);
PAINT GREEN (-1438 1662);
DISPLAY INVISIBLE (-1438 1662);
FORCEPROP 2 LAST CDS_XR_PAGE_TITLE CR-268 : @BASEBOARD_FAB2_LIB.BASEBOARD_FAB2(SCH_1):PAGE268
J 0
(-9340 6900);
DISPLAY 0.638298 (-9340 6900);
PAINT PINK (-9340 6900);
DISPLAY INVISIBLE (-9340 6900);
FORCENOTE
$CDS_IMAGE|Fast_Prochot_Block_Diagram_0411.jpg|8125|3250
(-5425 4075) 0;
DISPLAY LEFT (-5425 4075);
QUIT
